(kicad_pcb
	(version 20260206)
	(generator "pcbnew")
	(generator_version "10.0")
	(general
		(thickness 1.6)
		(legacy_teardrops no)
	)
	(paper "A4")
	(title_block
		(title "dpb — 14545-sa.0730WZS0815.brd")
		(comment 1 "Honey Badger (Wiwynn) / footprints 947-949 of 1066")
	)
	(layers
		(0 "F.Cu" signal "TOP")
		(4 "In1.Cu" signal "L2GND")
		(6 "In2.Cu" signal "L3")
		(8 "In3.Cu" signal "L4VCC")
		(10 "In4.Cu" signal "L5VCC")
		(12 "In5.Cu" signal "L6")
		(14 "In6.Cu" signal "L7GND")
		(2 "B.Cu" signal "BOTTOM")
		(9 "F.Adhes" user "F.Adhesive")
		(11 "B.Adhes" user "B.Adhesive")
		(13 "F.Paste" user "Package Geometry/Pastemask Top")
		(15 "B.Paste" user "Package Geometry/Pastemask Bottom")
		(5 "F.SilkS" user "Ref Des/Silkscreen Top")
		(7 "B.SilkS" user "Ref Des/Silkscreen Bottom")
		(1 "F.Mask" user "Board Geometry/Soldermask Top")
		(3 "B.Mask" user "Board Geometry/Soldermask Bottom")
		(17 "Dwgs.User" user "User.Drawings")
		(19 "Cmts.User" user "User.Comments")
		(21 "Eco1.User" user "User.Eco1")
		(23 "Eco2.User" user "User.Eco2")
		(25 "Edge.Cuts" user "Board Geometry/Outline")
		(27 "Margin" user)
		(31 "F.CrtYd" user "Package Geometry/Place Bound Top")
		(29 "B.CrtYd" user "Package Geometry/Place Bound Bottom")
		(35 "F.Fab" user "Ref Des/Assembly Top")
		(33 "B.Fab" user "Ref Des/Assembly Bottom")
	)
	(footprint ""
		(layer "F.Cu")
		(at 2.500122 -305.204622 -90)
		(property "Reference" "CN8"
			(at 0 0 270)
			(layer "F.SilkS")
			(hide yes)
			(effects
				(font
					(size 1.27 1.27)
				)
			)
		)
		(property "Value" "PCISLT36-27-GP"
			(at 5.281422 -7.491476 270)
			(unlocked yes)
			(layer "F.Fab")
			(hide yes)
			(effects
				(font
					(size 1.016 1.016)
					(thickness 0.1524)
				)
			)
		)
		(property "Device Type" "G630H3612248EU"
			(at 5.281422 -9.015476 270)
			(unlocked yes)
			(layer "F.Fab")
			(hide yes)
			(effects
				(font
					(size 1.016 1.016)
					(thickness 0.1524)
				)
			)
		)
		(duplicate_pad_numbers_are_jumpers no)
		(fp_line
			(start -14.899894 2.499868)
			(end -1.450086 2.499868)
			(stroke
				(width 0.1524)
				(type default)
			)
			(layer "F.SilkS")
		)
		(fp_line
			(start -1.450086 2.499868)
			(end -0.94996 1.999742)
			(stroke
				(width 0.1524)
				(type default)
			)
			(layer "F.SilkS")
		)
		(fp_line
			(start 1.450086 2.499868)
			(end 18.899886 2.499868)
			(stroke
				(width 0.1524)
				(type default)
			)
			(layer "F.SilkS")
		)
		(fp_line
			(start 18.899886 2.499868)
			(end 19.400012 1.999742)
			(stroke
				(width 0.1524)
				(type default)
			)
			(layer "F.SilkS")
		)
		(fp_line
			(start -15.40002 1.999742)
			(end -14.899894 2.499868)
			(stroke
				(width 0.1524)
				(type default)
			)
			(layer "F.SilkS")
		)
		(fp_line
			(start -0.94996 1.999742)
			(end -0.94996 -2.55016)
			(stroke
				(width 0.1524)
				(type default)
			)
			(layer "F.SilkS")
		)
		(fp_line
			(start 0.94996 1.999742)
			(end 1.450086 2.499868)
			(stroke
				(width 0.1524)
				(type default)
			)
			(layer "F.SilkS")
		)
		(fp_line
			(start 19.400012 1.999742)
			(end 19.400012 -4.064)
			(stroke
				(width 0.1524)
				(type default)
			)
			(layer "F.SilkS")
		)
		(fp_line
			(start 0.94996 -2.539746)
			(end 0.94996 1.999742)
			(stroke
				(width 0.1524)
				(type default)
			)
			(layer "F.SilkS")
		)
		(fp_line
			(start 0.94996 -2.55016)
			(end 0.94996 -2.539746)
			(stroke
				(width 0.1524)
				(type default)
			)
			(layer "F.SilkS")
		)
		(fp_line
			(start -15.40002 -4.064)
			(end -15.40002 1.999742)
			(stroke
				(width 0.1524)
				(type default)
			)
			(layer "F.SilkS")
		)
		(fp_line
			(start 19.400012 -4.064)
			(end -15.40002 -4.064)
			(stroke
				(width 0.1524)
				(type default)
			)
			(layer "F.SilkS")
		)
		(fp_line
			(start 11.6713 -4.1529)
			(end 11.2903 -4.1529)
			(stroke
				(width 0.3302)
				(type default)
			)
			(layer "F.SilkS")
		)
		(fp_arc
			(start -0.94996 -2.55016)
			(mid 0 -3.50012)
			(end 0.94996 -2.55016)
			(stroke
				(width 0.1524)
				(type default)
			)
			(layer "F.SilkS")
		)
		(fp_poly
			(pts
				(xy 11.474704 -4.1402) (xy 10.966704 -4.6482) (xy 11.982704 -4.6482)
			)
			(stroke
				(width 0)
				(type default)
			)
			(fill yes)
			(layer "F.SilkS")
		)
		(fp_poly
			(pts
				(xy -10.4902 14.986) (xy -10.4902 4.8006) (xy -15.3924 4.8006) (xy -15.3924 -3.81) (xy 19.4056 -3.81)
				(xy 19.4056 4.8006) (xy 14.5034 4.8006) (xy 14.5034 14.986)
			)
			(stroke
				(width 0)
				(type default)
			)
			(fill no)
			(layer "B.CrtYd")
		)
		(fp_poly
			(pts
				(xy -10.9982 15.494) (xy -10.9982 5.3086) (xy -15.9004 5.3086) (xy -15.9004 -4.318) (xy 19.9136 -4.318)
				(xy 19.9136 5.3086) (xy 15.0114 5.3086) (xy 15.0114 15.494) (xy 0.00254 15.494) (xy 0.00254 14.986)
				(xy 14.5034 14.986) (xy 14.5034 4.8006) (xy 19.4056 4.8006) (xy 19.4056 -3.81) (xy -15.3924 -3.81)
				(xy -15.3924 4.8006) (xy -10.4902 4.8006) (xy -10.4902 14.986) (xy -0.00254 14.986) (xy -0.00254 15.494)
			)
			(stroke
				(width 0)
				(type default)
			)
			(fill no)
			(layer "B.CrtYd")
		)
		(fp_poly
			(pts
				(xy -10.4902 14.986) (xy -10.4902 4.8006) (xy -15.3924 4.8006) (xy -15.3924 -3.81) (xy 19.4056 -3.81)
				(xy 19.4056 4.8006) (xy 14.5034 4.8006) (xy 14.5034 14.986)
			)
			(stroke
				(width 0)
				(type default)
			)
			(fill no)
			(layer "F.CrtYd")
		)
		(fp_poly
			(pts
				(xy -10.9982 15.494) (xy -10.9982 5.3086) (xy -15.9004 5.3086) (xy -15.9004 -4.318) (xy 19.9136 -4.318)
				(xy 19.9136 5.3086) (xy 15.0114 5.3086) (xy 15.0114 15.494) (xy 0.00254 15.494) (xy 0.00254 14.986)
				(xy 14.5034 14.986) (xy 14.5034 4.8006) (xy 19.4056 4.8006) (xy 19.4056 -3.81) (xy -15.3924 -3.81)
				(xy -15.3924 4.8006) (xy -10.4902 4.8006) (xy -10.4902 14.986) (xy -0.00254 14.986) (xy -0.00254 15.494)
			)
			(stroke
				(width 0)
				(type default)
			)
			(fill no)
			(layer "F.CrtYd")
		)
		(fp_poly
			(pts
				(xy -10.9982 15.494) (xy -10.9982 5.3086) (xy -15.9004 5.3086) (xy -15.9004 -4.318) (xy 19.9136 -4.318)
				(xy 19.9136 5.3086) (xy 15.0114 5.3086) (xy 15.0114 15.494)
			)
			(stroke
				(width 0)
				(type default)
			)
			(fill no)
			(layer "B.Fab")
		)
		(fp_poly
			(pts
				(xy -10.9982 15.494) (xy -10.9982 5.3086) (xy -15.9004 5.3086) (xy -15.9004 -4.318) (xy 19.9136 -4.318)
				(xy 19.9136 5.3086) (xy 15.0114 5.3086) (xy 15.0114 15.494)
			)
			(stroke
				(width 0)
				(type default)
			)
			(fill no)
			(layer "F.Fab")
		)
		(fp_text user "Slit"
			(at 1.9304 5.088636 270)
			(unlocked yes)
			(layer "F.SilkS")
			(effects
				(font
					(size 1.016 1.016)
					(thickness 0.1524)
				)
				(justify left)
			)
		)
		(pad "" np_thru_hole circle
			(at -12.300204 0 270)
			(size 0.254 0.254)
			(drill 2.3114)
			(layers "*.Cu" "*.Mask")
			(clearance 1.3843)
			(thermal_gap 1.3843)
		)
		(pad "" np_thru_hole circle
			(at 16.299942 0 270)
			(size 0.254 0.254)
			(drill 2.3114)
			(layers "*.Cu" "*.Mask")
			(clearance 1.3843)
			(thermal_gap 1.3843)
		)
		(pad "A1" smd rect
			(at 11.500104 -0.309118 270)
			(size 0.7112 3.6068)
			(drill
				(offset 0 -0.381)
			)
			(layers "F.Cu" "F.Mask" "F.Paste")
			(net "PRSNT_A")
		)
		(pad "A2" smd rect
			(at 10.500106 -0.309118 270)
			(size 0.7112 3.6068)
			(drill
				(offset 0 -0.381)
			)
			(layers "F.Cu" "F.Mask" "F.Paste")
			(net "P12V")
		)
		(pad "A3" smd rect
			(at 9.500108 -0.309118 270)
			(size 0.7112 3.6068)
			(drill
				(offset 0 -0.381)
			)
			(layers "F.Cu" "F.Mask" "F.Paste")
			(net "P12V")
		)
		(pad "A4" smd rect
			(at 8.50011 -0.309118 270)
			(size 0.7112 3.6068)
			(drill
				(offset 0 -0.381)
			)
			(layers "F.Cu" "F.Mask" "F.Paste")
			(net "P12V")
		)
		(pad "A5" smd rect
			(at 7.500112 -0.309118 270)
			(size 0.7112 3.6068)
			(drill
				(offset 0 -0.381)
			)
			(layers "F.Cu" "F.Mask" "F.Paste")
			(net "P12V")
		)
		(pad "A6" smd rect
			(at 6.500114 -0.309118 270)
			(size 0.7112 3.6068)
			(drill
				(offset 0 -0.381)
			)
			(layers "F.Cu" "F.Mask" "F.Paste")
			(net "P12V")
		)
		(pad "A7" smd rect
			(at 5.500116 -0.309118 270)
			(size 0.7112 3.6068)
			(drill
				(offset 0 -0.381)
			)
			(layers "F.Cu" "F.Mask" "F.Paste")
			(net "P12V")
		)
		(pad "A8" smd rect
			(at 4.500118 -0.309118 270)
			(size 0.7112 3.6068)
			(drill
				(offset 0 -0.381)
			)
			(layers "F.Cu" "F.Mask" "F.Paste")
			(net "P12V")
		)
		(pad "A9" smd rect
			(at 3.50012 -0.309118 270)
			(size 0.7112 3.6068)
			(drill
				(offset 0 -0.381)
			)
			(layers "F.Cu" "F.Mask" "F.Paste")
			(net "Net_104")
		)
		(pad "A10" smd rect
			(at 2.500122 -0.309118 270)
			(size 0.7112 3.6068)
			(drill
				(offset 0 -0.381)
			)
			(layers "F.Cu" "F.Mask" "F.Paste")
			(net "Net_103")
		)
		(pad "A11" smd rect
			(at 1.500124 -0.309118 270)
			(size 0.7112 3.6068)
			(drill
				(offset 0 -0.381)
			)
			(layers "F.Cu" "F.Mask" "F.Paste")
			(net "Net_102")
		)
		(pad "A12" smd rect
			(at -1.500124 -0.309118 270)
			(size 0.7112 3.6068)
			(drill
				(offset 0 -0.381)
			)
			(layers "F.Cu" "F.Mask" "F.Paste")
			(net "Net_111")
		)
		(pad "A13" smd rect
			(at -2.500122 -0.309118 270)
			(size 0.7112 3.6068)
			(drill
				(offset 0 -0.381)
			)
			(layers "F.Cu" "F.Mask" "F.Paste")
			(net "GND")
		)
		(pad "A14" smd rect
			(at -3.50012 -0.309118 270)
			(size 0.7112 3.6068)
			(drill
				(offset 0 -0.381)
			)
			(layers "F.Cu" "F.Mask" "F.Paste")
			(net "Net_110")
		)
		(pad "A15" smd rect
			(at -4.500118 -0.309118 270)
			(size 0.7112 3.6068)
			(drill
				(offset 0 -0.381)
			)
			(layers "F.Cu" "F.Mask" "F.Paste")
			(net "Net_109")
		)
		(pad "A16" smd rect
			(at -5.500116 -0.309118 270)
			(size 0.7112 3.6068)
			(drill
				(offset 0 -0.381)
			)
			(layers "F.Cu" "F.Mask" "F.Paste")
			(net "GND")
		)
		(pad "A17" smd rect
			(at -6.500114 -0.309118 270)
			(size 0.7112 3.6068)
			(drill
				(offset 0 -0.381)
			)
			(layers "F.Cu" "F.Mask" "F.Paste")
			(net "Net_114")
		)
		(pad "A18" smd rect
			(at -7.500112 -0.309118 270)
			(size 0.7112 3.6068)
			(drill
				(offset 0 -0.381)
			)
			(layers "F.Cu" "F.Mask" "F.Paste")
			(net "GND")
		)
		(pad "B1" smd rect
			(at 11.500104 -0.690118 270)
			(size 0.7112 3.6068)
			(layers "F.Cu" "F.Mask" "F.Paste")
			(net "GND")
		)
		(pad "B2" smd rect
			(at 10.500106 -0.690118 270)
			(size 0.7112 3.6068)
			(layers "F.Cu" "F.Mask" "F.Paste")
			(net "GND")
		)
		(pad "B3" smd rect
			(at 9.500108 -0.690118 270)
			(size 0.7112 3.6068)
			(layers "F.Cu" "F.Mask" "F.Paste")
			(net "GND")
		)
		(pad "B4" smd rect
			(at 8.50011 -0.690118 270)
			(size 0.7112 3.6068)
			(layers "F.Cu" "F.Mask" "F.Paste")
			(net "GND")
		)
		(pad "B5" smd rect
			(at 7.500112 -0.690118 270)
			(size 0.7112 3.6068)
			(layers "F.Cu" "F.Mask" "F.Paste")
			(net "GND")
		)
		(pad "B6" smd rect
			(at 6.500114 -0.690118 270)
			(size 0.7112 3.6068)
			(layers "F.Cu" "F.Mask" "F.Paste")
			(net "GND")
		)
		(pad "B7" smd rect
			(at 5.500116 -0.690118 270)
			(size 0.7112 3.6068)
			(layers "F.Cu" "F.Mask" "F.Paste")
			(net "GND")
		)
		(pad "B8" smd rect
			(at 4.500118 -0.690118 270)
			(size 0.7112 3.6068)
			(layers "F.Cu" "F.Mask" "F.Paste")
			(net "Net_108")
		)
		(pad "B9" smd rect
			(at 3.50012 -0.690118 270)
			(size 0.7112 3.6068)
			(layers "F.Cu" "F.Mask" "F.Paste")
			(net "Net_107")
		)
		(pad "B10" smd rect
			(at 2.500122 -0.690118 270)
			(size 0.7112 3.6068)
			(layers "F.Cu" "F.Mask" "F.Paste")
			(net "Net_106")
		)
		(pad "B11" smd rect
			(at 1.500124 -0.690118 270)
			(size 0.7112 3.6068)
			(layers "F.Cu" "F.Mask" "F.Paste")
			(net "Net_105")
		)
		(pad "B12" smd rect
			(at -1.500124 -0.690118 270)
			(size 0.7112 3.6068)
			(layers "F.Cu" "F.Mask" "F.Paste")
			(net "GND")
		)
		(pad "B13" smd rect
			(at -2.500122 -0.690118 270)
			(size 0.7112 3.6068)
			(layers "F.Cu" "F.Mask" "F.Paste")
			(net "Net_113")
		)
		(pad "B14" smd rect
			(at -3.50012 -0.690118 270)
			(size 0.7112 3.6068)
			(layers "F.Cu" "F.Mask" "F.Paste")
			(net "Net_112")
		)
		(pad "B15" smd rect
			(at -4.500118 -0.690118 270)
			(size 0.7112 3.6068)
			(layers "F.Cu" "F.Mask" "F.Paste")
			(net "GND")
		)
		(pad "B16" smd rect
			(at -5.500116 -0.690118 270)
			(size 0.7112 3.6068)
			(layers "F.Cu" "F.Mask" "F.Paste")
			(net "Net_116")
		)
		(pad "B17" smd rect
			(at -6.500114 -0.690118 270)
			(size 0.7112 3.6068)
			(layers "F.Cu" "F.Mask" "F.Paste")
			(net "Net_115")
		)
		(pad "B18" smd rect
			(at -7.500112 -0.690118 270)
			(size 0.7112 3.6068)
			(layers "F.Cu" "F.Mask" "F.Paste")
			(net "GND")
		)
		(zone
			(layers "F.Cu" "B.Cu" "In1.Cu" "In2.Cu" "In3.Cu" "In4.Cu" "In5.Cu" "In6.Cu")
			(hatch none 0.5)
			(connect_pads
				(clearance 0)
			)
			(min_thickness 0.25)
			(keepout
				(tracks not_allowed)
				(vias allowed)
				(pads allowed)
				(copperpour not_allowed)
				(footprints allowed)
			)
			(placement
				(enabled no)
				(sheetname "")
			)
			(fill
				(thermal_gap 0.5)
				(thermal_bridge_width 0.5)
				(island_removal_mode 0)
			)
			(polygon
				(pts
					(arc
						(start 3.960622 -317.504826)
						(mid 1.039622 -317.504826)
						(end 3.960622 -317.504826)
					)
				)
			)
		)
		(zone
			(layers "F.Cu" "B.Cu" "In1.Cu" "In2.Cu" "In3.Cu" "In4.Cu" "In5.Cu" "In6.Cu")
			(hatch none 0.5)
			(connect_pads
				(clearance 0)
			)
			(min_thickness 0.25)
			(keepout
				(tracks not_allowed)
				(vias allowed)
				(pads allowed)
				(copperpour not_allowed)
				(footprints allowed)
			)
			(placement
				(enabled no)
				(sheetname "")
			)
			(fill
				(thermal_gap 0.5)
				(thermal_bridge_width 0.5)
				(island_removal_mode 0)
			)
			(polygon
				(pts
					(arc
						(start 3.960622 -288.90468)
						(mid 1.039622 -288.90468)
						(end 3.960622 -288.90468)
					)
				)
			)
		)
	)
	(footprint ""
		(layer "F.Cu")
		(at 235.838746 -27.9527)
		(property "Reference" "PC13"
			(at 0 0 0)
			(layer "F.SilkS")
			(hide yes)
			(effects
				(font
					(size 1.27 1.27)
				)
			)
		)
		(property "Value" "SC680P50V2KX-2GP"
			(at 1.1811 -2.7051 0)
			(unlocked yes)
			(layer "F.Fab")
			(hide yes)
			(effects
				(font
					(size 1.016 1.016)
					(thickness 0.1524)
				)
			)
		)
		(property "Device Type" "C402H22"
			(at 1.1811 -4.2291 0)
			(unlocked yes)
			(layer "F.Fab")
			(hide yes)
			(effects
				(font
					(size 1.016 1.016)
					(thickness 0.1524)
				)
			)
		)
		(duplicate_pad_numbers_are_jumpers no)
		(fp_rect
			(start -0.4318 0.9525)
			(end 0.4318 -0.9525)
			(stroke
				(width 0)
				(type default)
			)
			(fill no)
			(layer "F.CrtYd")
		)
		(fp_rect
			(start -0.4318 0.9525)
			(end 0.4318 -0.9525)
			(stroke
				(width 0)
				(type default)
			)
			(fill no)
			(layer "F.Fab")
		)
		(pad "1" smd custom
			(at 0 -0.4445)
			(size 0.1524 0.1524)
			(layers "F.Cu" "F.Mask" "F.Paste")
			(net "P5VA_LL_NET")
			(options
				(clearance outline)
				(anchor circle)
			)
			(primitives
				(gr_poly
					(pts
						(arc
							(start 0.3048 -0.2032)
							(mid 0.275042 -0.275042)
							(end 0.2032 -0.3048)
						)
						(arc
							(start -0.2032 -0.3048)
							(mid -0.275042 -0.275042)
							(end -0.3048 -0.2032)
						)
						(arc
							(start -0.3048 0.2032)
							(mid -0.275042 0.275042)
							(end -0.2032 0.3048)
						)
						(arc
							(start 0.2032 0.3048)
							(mid 0.275042 0.275042)
							(end 0.3048 0.2032)
						)
					)
					(width 0)
					(fill yes)
				)
			)
		)
		(pad "2" smd custom
			(at 0 0.4445)
			(size 0.1524 0.1524)
			(layers "F.Cu" "F.Mask" "F.Paste")
			(net "P5VA_VFB")
			(options
				(clearance outline)
				(anchor circle)
			)
			(primitives
				(gr_poly
					(pts
						(arc
							(start 0.3048 -0.2032)
							(mid 0.275042 -0.275042)
							(end 0.2032 -0.3048)
						)
						(arc
							(start -0.2032 -0.3048)
							(mid -0.275042 -0.275042)
							(end -0.3048 -0.2032)
						)
						(arc
							(start -0.3048 0.2032)
							(mid -0.275042 0.275042)
							(end -0.2032 0.3048)
						)
						(arc
							(start 0.2032 0.3048)
							(mid 0.275042 0.275042)
							(end 0.3048 0.2032)
						)
					)
					(width 0)
					(fill yes)
				)
			)
		)
	)
	(footprint ""
		(layer "F.Cu")
		(at 223.4946 -442.1378 -90)
		(property "Reference" "PR63"
			(at 0 0 270)
			(layer "F.SilkS")
			(hide yes)
			(effects
				(font
					(size 1.27 1.27)
				)
			)
		)
		(property "Value" "0R0603-PAD-2-GP-U"
			(at 2.1209 -0.1397 270)
			(unlocked yes)
			(layer "F.Fab")
			(hide yes)
			(effects
				(font
					(size 1.016 1.016)
					(thickness 0.1524)
				)
			)
		)
		(property "Device Type" "0R0603-PAD-1-U"
			(at 2.1209 -1.6637 270)
			(unlocked yes)
			(layer "F.Fab")
			(hide yes)
			(effects
				(font
					(size 1.016 1.016)
					(thickness 0.1524)
				)
			)
		)
		(duplicate_pad_numbers_are_jumpers no)
		(fp_rect
			(start -0.5842 1.3335)
			(end 0.5842 -1.3335)
			(stroke
				(width 0)
				(type default)
			)
			(fill no)
			(layer "F.CrtYd")
		)
		(fp_rect
			(start -0.5842 1.3335)
			(end 0.5842 -1.3335)
			(stroke
				(width 0)
				(type default)
			)
			(fill no)
			(layer "F.Fab")
		)
		(pad "1" smd custom
			(at 0 -0.762 270)
			(size 0.2159 0.2159)
			(layers "F.Cu" "F.Mask" "F.Paste")
			(net "P12V")
			(options
				(clearance outline)
				(anchor circle)
			)
			(primitives
				(gr_poly
					(pts
						(arc
							(start -0.3302 -0.5842)
							(mid -0.402042 -0.554442)
							(end -0.4318 -0.4826)
						)
						(arc
							(start -0.4318 0.4826)
							(mid -0.402042 0.554442)
							(end -0.3302 0.5842)
						)
						(arc
							(start 0.3302 0.5842)
							(mid 0.402042 0.554442)
							(end 0.4318 0.4826)
						)
						(arc
							(start 0.4318 -0.4826)
							(mid 0.402042 -0.554442)
							(end 0.3302 -0.5842)
						)
					)
					(width 0)
					(fill yes)
				)
			)
		)
		(pad "2" smd custom
			(at 0 0.762 270)
			(size 0.2159 0.2159)
			(layers "F.Cu" "F.Mask" "F.Paste")
			(net "P3V3_IN")
			(options
				(clearance outline)
				(anchor circle)
			)
			(primitives
				(gr_poly
					(pts
						(arc
							(start -0.4318 0.4826)
							(mid -0.402042 0.554442)
							(end -0.3302 0.5842)
						)
						(arc
							(start 0.3302 0.5842)
							(mid 0.402042 0.554442)
							(end 0.4318 0.4826)
						)
						(arc
							(start 0.4318 -0.4826)
							(mid 0.402042 -0.554442)
							(end 0.3302 -0.5842)
						)
						(arc
							(start -0.3302 -0.5842)
							(mid -0.402042 -0.554442)
							(end -0.4318 -0.4826)
						)
					)
					(width 0)
					(fill yes)
				)
			)
		)
	)
)
